(kicad_pcb
	(version 20260206)
	(generator "pcbnew")
	(generator_version "10.0")
	(general
		(thickness 1.6)
		(legacy_teardrops no)
	)
	(paper "A4")
	(title_block
		(title "01162023_DA0F0TEBIF0_F0T_Expander_BD_F_brd_V02_OCP.brd")
		(comment 1 "Grand Teton / footprint 5622 of 9728 (PEX2), pads 1768-1882 of 2397")
	)
	(layers
		(0 "F.Cu" signal "TOP")
		(4 "In1.Cu" signal "GND")
		(6 "In2.Cu" signal "VCC")
		(8 "In3.Cu" signal "VCC1")
		(10 "In4.Cu" signal "GND1")
		(12 "In5.Cu" signal "IN1")
		(14 "In6.Cu" signal "GND2")
		(16 "In7.Cu" signal "IN2")
		(18 "In8.Cu" signal "GND3")
		(20 "In9.Cu" signal "IN3")
		(22 "In10.Cu" signal "GND4")
		(24 "In11.Cu" signal "IN4")
		(26 "In12.Cu" signal "GND5")
		(28 "In13.Cu" signal "IN5")
		(30 "In14.Cu" signal "GND6")
		(32 "In15.Cu" signal "IN6")
		(34 "In16.Cu" signal "GND7")
		(2 "B.Cu" signal "BOTTOM")
		(9 "F.Adhes" user "F.Adhesive")
		(11 "B.Adhes" user "B.Adhesive")
		(13 "F.Paste" user "Package Geometry/Pastemask Top")
		(15 "B.Paste" user "Package Geometry/Pastemask Bottom")
		(5 "F.SilkS" user "Ref Des/Silkscreen Top")
		(7 "B.SilkS" user "Ref Des/Silkscreen Bottom")
		(1 "F.Mask" user "Board Geometry/Soldermask Top")
		(3 "B.Mask" user "Board Geometry/Soldermask Bottom")
		(17 "Dwgs.User" user "User.Drawings")
		(19 "Cmts.User" user "User.Comments")
		(21 "Eco1.User" user "User.Eco1")
		(23 "Eco2.User" user "User.Eco2")
		(25 "Edge.Cuts" user "Board Geometry/Outline")
		(27 "Margin" user)
		(31 "F.CrtYd" user "Package Geometry/Place Bound Top")
		(29 "B.CrtYd" user "Package Geometry/Place Bound Bottom")
		(35 "F.Fab" user "Ref Des/Assembly Top")
		(33 "B.Fab" user "Ref Des/Assembly Bottom")
	)
	(footprint ""
		(layer "F.Cu")
		(at 291.84981 -295.89984)
		(property "Reference" "PEX2"
			(at -3.35153 35.56762 0)
			(unlocked yes)
			(layer "F.SilkS")
			(effects
				(font
					(size 2.032 1.524)
					(thickness 0.1524)
				)
				(justify left)
			)
		)
		(property "Value" ""
			(at 0 0 0)
			(layer "F.Fab")
			(effects
				(font
					(size 1.27 1.27)
				)
			)
		)
		(duplicate_pad_numbers_are_jumpers no)
		(pad "H8" smd circle
			(at -16.150082 -16.150082)
			(size 0.4572 0.4572)
			(layers "F.Cu" "F.Mask" "F.Paste")
			(net "P5E_PEX2_STN6_TX_DN<111>")
		)
		(pad "H9" smd circle
			(at -15.200122 -16.150082)
			(size 0.4572 0.4572)
			(layers "F.Cu" "F.Mask" "F.Paste")
			(net "GND")
		)
		(pad "H10" smd circle
			(at -14.249908 -16.150082)
			(size 0.4572 0.4572)
			(layers "F.Cu" "F.Mask" "F.Paste")
			(net "P5E_PEX2_STN6_TX_DN<109>")
		)
		(pad "H11" smd circle
			(at -13.299948 -16.150082)
			(size 0.4572 0.4572)
			(layers "F.Cu" "F.Mask" "F.Paste")
			(net "GND")
		)
		(pad "H12" smd circle
			(at -12.349988 -16.150082)
			(size 0.4572 0.4572)
			(layers "F.Cu" "F.Mask" "F.Paste")
			(net "P5E_PEX2_STN6_TX_DN<107>")
		)
		(pad "H13" smd circle
			(at -11.400028 -16.150082)
			(size 0.4572 0.4572)
			(layers "F.Cu" "F.Mask" "F.Paste")
			(net "GND")
		)
		(pad "H14" smd circle
			(at -10.450068 -16.150082)
			(size 0.4572 0.4572)
			(layers "F.Cu" "F.Mask" "F.Paste")
			(net "P5E_PEX2_STN6_TX_DN<105>")
		)
		(pad "H15" smd circle
			(at -9.500108 -16.150082)
			(size 0.4572 0.4572)
			(layers "F.Cu" "F.Mask" "F.Paste")
			(net "GND")
		)
		(pad "H16" smd circle
			(at -8.549894 -16.150082)
			(size 0.4572 0.4572)
			(layers "F.Cu" "F.Mask" "F.Paste")
			(net "P5E_PEX2_STN6_TX_DN<103>")
		)
		(pad "H17" smd circle
			(at -7.599934 -16.150082)
			(size 0.4572 0.4572)
			(layers "F.Cu" "F.Mask" "F.Paste")
			(net "GND")
		)
		(pad "H18" smd circle
			(at -6.649974 -16.150082)
			(size 0.4572 0.4572)
			(layers "F.Cu" "F.Mask" "F.Paste")
			(net "P5E_PEX2_STN6_TX_DN<101>")
		)
		(pad "H19" smd circle
			(at -5.700014 -16.150082)
			(size 0.4572 0.4572)
			(layers "F.Cu" "F.Mask" "F.Paste")
			(net "GND")
		)
		(pad "H20" smd circle
			(at -4.750054 -16.150082)
			(size 0.4572 0.4572)
			(layers "F.Cu" "F.Mask" "F.Paste")
			(net "P5E_PEX2_STN6_TX_DN<99>")
		)
		(pad "H21" smd circle
			(at -3.800094 -16.150082)
			(size 0.4572 0.4572)
			(layers "F.Cu" "F.Mask" "F.Paste")
			(net "GND")
		)
		(pad "H22" smd circle
			(at -2.84988 -16.150082)
			(size 0.4572 0.4572)
			(layers "F.Cu" "F.Mask" "F.Paste")
			(net "P5E_PEX2_STN6_TX_DN<97>")
		)
		(pad "H23" smd circle
			(at -1.89992 -16.150082)
			(size 0.4572 0.4572)
			(layers "F.Cu" "F.Mask" "F.Paste")
			(net "GND")
		)
		(pad "H24" smd circle
			(at -0.94996 -16.150082)
			(size 0.4572 0.4572)
			(layers "F.Cu" "F.Mask" "F.Paste")
			(net "P5E_PEX2_STN5_TX_DN<80>")
		)
		(pad "H25" smd circle
			(at 0 -16.150082)
			(size 0.4572 0.4572)
			(layers "F.Cu" "F.Mask" "F.Paste")
			(net "GND")
		)
		(pad "H26" smd circle
			(at 0.94996 -16.150082)
			(size 0.4572 0.4572)
			(layers "F.Cu" "F.Mask" "F.Paste")
			(net "P5E_PEX2_STN5_TX_DN<82>")
		)
		(pad "H27" smd circle
			(at 1.89992 -16.150082)
			(size 0.4572 0.4572)
			(layers "F.Cu" "F.Mask" "F.Paste")
			(net "GND")
		)
		(pad "H28" smd circle
			(at 2.84988 -16.150082)
			(size 0.4572 0.4572)
			(layers "F.Cu" "F.Mask" "F.Paste")
			(net "P5E_PEX2_STN5_TX_DN<84>")
		)
		(pad "H29" smd circle
			(at 3.800094 -16.150082)
			(size 0.4572 0.4572)
			(layers "F.Cu" "F.Mask" "F.Paste")
			(net "GND")
		)
		(pad "H30" smd circle
			(at 4.750054 -16.150082)
			(size 0.4572 0.4572)
			(layers "F.Cu" "F.Mask" "F.Paste")
			(net "P5E_PEX2_STN5_TX_DN<86>")
		)
		(pad "H31" smd circle
			(at 5.700014 -16.150082)
			(size 0.4572 0.4572)
			(layers "F.Cu" "F.Mask" "F.Paste")
			(net "GND")
		)
		(pad "H32" smd circle
			(at 6.649974 -16.150082)
			(size 0.4572 0.4572)
			(layers "F.Cu" "F.Mask" "F.Paste")
			(net "P5E_PEX2_STN5_TX_DN<88>")
		)
		(pad "H33" smd circle
			(at 7.599934 -16.150082)
			(size 0.4572 0.4572)
			(layers "F.Cu" "F.Mask" "F.Paste")
			(net "GND")
		)
		(pad "H34" smd circle
			(at 8.549894 -16.150082)
			(size 0.4572 0.4572)
			(layers "F.Cu" "F.Mask" "F.Paste")
			(net "P5E_PEX2_STN5_TX_DN<90>")
		)
		(pad "H35" smd circle
			(at 9.500108 -16.150082)
			(size 0.4572 0.4572)
			(layers "F.Cu" "F.Mask" "F.Paste")
			(net "GND")
		)
		(pad "H36" smd circle
			(at 10.450068 -16.150082)
			(size 0.4572 0.4572)
			(layers "F.Cu" "F.Mask" "F.Paste")
			(net "P5E_PEX2_STN5_TX_DN<92>")
		)
		(pad "H37" smd circle
			(at 11.400028 -16.150082)
			(size 0.4572 0.4572)
			(layers "F.Cu" "F.Mask" "F.Paste")
			(net "GND")
		)
		(pad "H38" smd circle
			(at 12.349988 -16.150082)
			(size 0.4572 0.4572)
			(layers "F.Cu" "F.Mask" "F.Paste")
			(net "P5E_PEX2_STN5_TX_DN<94>")
		)
		(pad "H39" smd circle
			(at 13.299948 -16.150082)
			(size 0.4572 0.4572)
			(layers "F.Cu" "F.Mask" "F.Paste")
			(net "GND")
		)
		(pad "H40" smd circle
			(at 14.249908 -16.150082)
			(size 0.4572 0.4572)
			(layers "F.Cu" "F.Mask" "F.Paste")
			(net "P5E_PEX2_STN4_TX_DN<79>")
		)
		(pad "H41" smd circle
			(at 15.200122 -16.150082)
			(size 0.4572 0.4572)
			(layers "F.Cu" "F.Mask" "F.Paste")
			(net "GND")
		)
		(pad "H42" smd circle
			(at 16.150082 -16.150082)
			(size 0.4572 0.4572)
			(layers "F.Cu" "F.Mask" "F.Paste")
			(net "P5E_PEX2_STN4_TX_DN<77>")
		)
		(pad "H43" smd circle
			(at 17.100042 -16.150082)
			(size 0.4572 0.4572)
			(layers "F.Cu" "F.Mask" "F.Paste")
			(net "GND")
		)
		(pad "H44" smd circle
			(at 18.050002 -16.150082)
			(size 0.4572 0.4572)
			(layers "F.Cu" "F.Mask" "F.Paste")
			(net "P5E_PEX2_STN4_TX_DN<75>")
		)
		(pad "H45" smd circle
			(at 18.999962 -16.150082)
			(size 0.4572 0.4572)
			(layers "F.Cu" "F.Mask" "F.Paste")
			(net "GND")
		)
		(pad "H46" smd circle
			(at 19.949922 -16.150082)
			(size 0.4572 0.4572)
			(layers "F.Cu" "F.Mask" "F.Paste")
			(net "P5E_PEX2_STN4_TX_DN<73>")
		)
		(pad "H47" smd circle
			(at 20.899882 -16.150082)
			(size 0.4572 0.4572)
			(layers "F.Cu" "F.Mask" "F.Paste")
			(net "GND")
		)
		(pad "H48" smd circle
			(at 21.850096 -16.150082)
			(size 0.4572 0.4572)
			(layers "F.Cu" "F.Mask" "F.Paste")
			(net "P5E_PEX2_STN4_TX_DP<70>")
		)
		(pad "H49" smd circle
			(at 22.800056 -16.150082)
			(size 0.4572 0.4572)
			(layers "F.Cu" "F.Mask" "F.Paste")
			(net "P5E_PEX2_STN4_TX_DN<70>")
		)
		(pad "J1" smd circle
			(at -22.800056 -15.200122)
			(size 0.4572 0.4572)
			(layers "F.Cu" "F.Mask" "F.Paste")
			(net "GND")
		)
		(pad "J2" smd circle
			(at -21.850096 -15.200122)
			(size 0.4572 0.4572)
			(layers "F.Cu" "F.Mask" "F.Paste")
			(net "GND")
		)
		(pad "J3" smd circle
			(at -20.899882 -15.200122)
			(size 0.4572 0.4572)
			(layers "F.Cu" "F.Mask" "F.Paste")
			(net "GND")
		)
		(pad "J4" smd circle
			(at -19.949922 -15.200122)
			(size 0.4572 0.4572)
			(layers "F.Cu" "F.Mask" "F.Paste")
			(net "P5E_PEX2_STN7_TX_DP<124>")
		)
		(pad "J5" smd circle
			(at -18.999962 -15.200122)
			(size 0.4572 0.4572)
			(layers "F.Cu" "F.Mask" "F.Paste")
			(net "GND")
		)
		(pad "J6" smd circle
			(at -18.050002 -15.200122)
			(size 0.4572 0.4572)
			(layers "F.Cu" "F.Mask" "F.Paste")
			(net "P5E_PEX2_STN7_TX_DP<126>")
		)
		(pad "J7" smd circle
			(at -17.100042 -15.200122)
			(size 0.4572 0.4572)
			(layers "F.Cu" "F.Mask" "F.Paste")
			(net "GND")
		)
		(pad "J8" smd circle
			(at -16.150082 -15.200122)
			(size 0.4572 0.4572)
			(layers "F.Cu" "F.Mask" "F.Paste")
			(net "P5E_PEX2_STN6_TX_DP<111>")
		)
		(pad "J9" smd circle
			(at -15.200122 -15.200122)
			(size 0.4572 0.4572)
			(layers "F.Cu" "F.Mask" "F.Paste")
			(net "GND")
		)
		(pad "J10" smd circle
			(at -14.249908 -15.200122)
			(size 0.4572 0.4572)
			(layers "F.Cu" "F.Mask" "F.Paste")
			(net "P5E_PEX2_STN6_TX_DP<109>")
		)
		(pad "J11" smd circle
			(at -13.299948 -15.200122)
			(size 0.4572 0.4572)
			(layers "F.Cu" "F.Mask" "F.Paste")
			(net "GND")
		)
		(pad "J12" smd circle
			(at -12.349988 -15.200122)
			(size 0.4572 0.4572)
			(layers "F.Cu" "F.Mask" "F.Paste")
			(net "P5E_PEX2_STN6_TX_DP<107>")
		)
		(pad "J13" smd circle
			(at -11.400028 -15.200122)
			(size 0.4572 0.4572)
			(layers "F.Cu" "F.Mask" "F.Paste")
			(net "GND")
		)
		(pad "J14" smd circle
			(at -10.450068 -15.200122)
			(size 0.4572 0.4572)
			(layers "F.Cu" "F.Mask" "F.Paste")
			(net "P5E_PEX2_STN6_TX_DP<105>")
		)
		(pad "J15" smd circle
			(at -9.500108 -15.200122)
			(size 0.4572 0.4572)
			(layers "F.Cu" "F.Mask" "F.Paste")
			(net "GND")
		)
		(pad "J16" smd circle
			(at -8.549894 -15.200122)
			(size 0.4572 0.4572)
			(layers "F.Cu" "F.Mask" "F.Paste")
			(net "P5E_PEX2_STN6_TX_DP<103>")
		)
		(pad "J17" smd circle
			(at -7.599934 -15.200122)
			(size 0.4572 0.4572)
			(layers "F.Cu" "F.Mask" "F.Paste")
			(net "GND")
		)
		(pad "J18" smd circle
			(at -6.649974 -15.200122)
			(size 0.4572 0.4572)
			(layers "F.Cu" "F.Mask" "F.Paste")
			(net "P5E_PEX2_STN6_TX_DP<101>")
		)
		(pad "J19" smd circle
			(at -5.700014 -15.200122)
			(size 0.4572 0.4572)
			(layers "F.Cu" "F.Mask" "F.Paste")
			(net "GND")
		)
		(pad "J20" smd circle
			(at -4.750054 -15.200122)
			(size 0.4572 0.4572)
			(layers "F.Cu" "F.Mask" "F.Paste")
			(net "P5E_PEX2_STN6_TX_DP<99>")
		)
		(pad "J21" smd circle
			(at -3.800094 -15.200122)
			(size 0.4572 0.4572)
			(layers "F.Cu" "F.Mask" "F.Paste")
			(net "GND")
		)
		(pad "J22" smd circle
			(at -2.84988 -15.200122)
			(size 0.4572 0.4572)
			(layers "F.Cu" "F.Mask" "F.Paste")
			(net "P5E_PEX2_STN6_TX_DP<97>")
		)
		(pad "J23" smd circle
			(at -1.89992 -15.200122)
			(size 0.4572 0.4572)
			(layers "F.Cu" "F.Mask" "F.Paste")
			(net "GND")
		)
		(pad "J24" smd circle
			(at -0.94996 -15.200122)
			(size 0.4572 0.4572)
			(layers "F.Cu" "F.Mask" "F.Paste")
			(net "P5E_PEX2_STN5_TX_DP<80>")
		)
		(pad "J25" smd circle
			(at 0 -15.200122)
			(size 0.4572 0.4572)
			(layers "F.Cu" "F.Mask" "F.Paste")
			(net "GND")
		)
		(pad "J26" smd circle
			(at 0.94996 -15.200122)
			(size 0.4572 0.4572)
			(layers "F.Cu" "F.Mask" "F.Paste")
			(net "P5E_PEX2_STN5_TX_DP<82>")
		)
		(pad "J27" smd circle
			(at 1.89992 -15.200122)
			(size 0.4572 0.4572)
			(layers "F.Cu" "F.Mask" "F.Paste")
			(net "GND")
		)
		(pad "J28" smd circle
			(at 2.84988 -15.200122)
			(size 0.4572 0.4572)
			(layers "F.Cu" "F.Mask" "F.Paste")
			(net "P5E_PEX2_STN5_TX_DP<84>")
		)
		(pad "J29" smd circle
			(at 3.800094 -15.200122)
			(size 0.4572 0.4572)
			(layers "F.Cu" "F.Mask" "F.Paste")
			(net "GND")
		)
		(pad "J30" smd circle
			(at 4.750054 -15.200122)
			(size 0.4572 0.4572)
			(layers "F.Cu" "F.Mask" "F.Paste")
			(net "P5E_PEX2_STN5_TX_DP<86>")
		)
		(pad "J31" smd circle
			(at 5.700014 -15.200122)
			(size 0.4572 0.4572)
			(layers "F.Cu" "F.Mask" "F.Paste")
			(net "GND")
		)
		(pad "J32" smd circle
			(at 6.649974 -15.200122)
			(size 0.4572 0.4572)
			(layers "F.Cu" "F.Mask" "F.Paste")
			(net "P5E_PEX2_STN5_TX_DP<88>")
		)
		(pad "J33" smd circle
			(at 7.599934 -15.200122)
			(size 0.4572 0.4572)
			(layers "F.Cu" "F.Mask" "F.Paste")
			(net "GND")
		)
		(pad "J34" smd circle
			(at 8.549894 -15.200122)
			(size 0.4572 0.4572)
			(layers "F.Cu" "F.Mask" "F.Paste")
			(net "P5E_PEX2_STN5_TX_DP<90>")
		)
		(pad "J35" smd circle
			(at 9.500108 -15.200122)
			(size 0.4572 0.4572)
			(layers "F.Cu" "F.Mask" "F.Paste")
			(net "GND")
		)
		(pad "J36" smd circle
			(at 10.450068 -15.200122)
			(size 0.4572 0.4572)
			(layers "F.Cu" "F.Mask" "F.Paste")
			(net "P5E_PEX2_STN5_TX_DP<92>")
		)
		(pad "J37" smd circle
			(at 11.400028 -15.200122)
			(size 0.4572 0.4572)
			(layers "F.Cu" "F.Mask" "F.Paste")
			(net "GND")
		)
		(pad "J38" smd circle
			(at 12.349988 -15.200122)
			(size 0.4572 0.4572)
			(layers "F.Cu" "F.Mask" "F.Paste")
			(net "P5E_PEX2_STN5_TX_DP<94>")
		)
		(pad "J39" smd circle
			(at 13.299948 -15.200122)
			(size 0.4572 0.4572)
			(layers "F.Cu" "F.Mask" "F.Paste")
			(net "GND")
		)
		(pad "J40" smd circle
			(at 14.249908 -15.200122)
			(size 0.4572 0.4572)
			(layers "F.Cu" "F.Mask" "F.Paste")
			(net "P5E_PEX2_STN4_TX_DP<79>")
		)
		(pad "J41" smd circle
			(at 15.200122 -15.200122)
			(size 0.4572 0.4572)
			(layers "F.Cu" "F.Mask" "F.Paste")
			(net "GND")
		)
		(pad "J42" smd circle
			(at 16.150082 -15.200122)
			(size 0.4572 0.4572)
			(layers "F.Cu" "F.Mask" "F.Paste")
			(net "P5E_PEX2_STN4_TX_DP<77>")
		)
		(pad "J43" smd circle
			(at 17.100042 -15.200122)
			(size 0.4572 0.4572)
			(layers "F.Cu" "F.Mask" "F.Paste")
			(net "GND")
		)
		(pad "J44" smd circle
			(at 18.050002 -15.200122)
			(size 0.4572 0.4572)
			(layers "F.Cu" "F.Mask" "F.Paste")
			(net "P5E_PEX2_STN4_TX_DP<75>")
		)
		(pad "J45" smd circle
			(at 18.999962 -15.200122)
			(size 0.4572 0.4572)
			(layers "F.Cu" "F.Mask" "F.Paste")
			(net "GND")
		)
		(pad "J46" smd circle
			(at 19.949922 -15.200122)
			(size 0.4572 0.4572)
			(layers "F.Cu" "F.Mask" "F.Paste")
			(net "P5E_PEX2_STN4_TX_DP<73>")
		)
		(pad "J47" smd circle
			(at 20.899882 -15.200122)
			(size 0.4572 0.4572)
			(layers "F.Cu" "F.Mask" "F.Paste")
			(net "GND")
		)
		(pad "J48" smd circle
			(at 21.850096 -15.200122)
			(size 0.4572 0.4572)
			(layers "F.Cu" "F.Mask" "F.Paste")
			(net "GND")
		)
		(pad "J49" smd circle
			(at 22.800056 -15.200122)
			(size 0.4572 0.4572)
			(layers "F.Cu" "F.Mask" "F.Paste")
			(net "GND")
		)
		(pad "K1" smd circle
			(at -22.800056 -14.249908)
			(size 0.4572 0.4572)
			(layers "F.Cu" "F.Mask" "F.Paste")
			(net "P5E_PEX2_STN7_RX_DN<121>")
		)
		(pad "K2" smd circle
			(at -21.850096 -14.249908)
			(size 0.4572 0.4572)
			(layers "F.Cu" "F.Mask" "F.Paste")
			(net "P5E_PEX2_STN7_RX_DP<121>")
		)
		(pad "K3" smd circle
			(at -20.899882 -14.249908)
			(size 0.4572 0.4572)
			(layers "F.Cu" "F.Mask" "F.Paste")
			(net "GND")
		)
		(pad "K4" smd circle
			(at -19.949922 -14.249908)
			(size 0.4572 0.4572)
			(layers "F.Cu" "F.Mask" "F.Paste")
			(net "GND")
		)
		(pad "K5" smd circle
			(at -18.999962 -14.249908)
			(size 0.4572 0.4572)
			(layers "F.Cu" "F.Mask" "F.Paste")
			(net "GND")
		)
		(pad "K6" smd circle
			(at -18.050002 -14.249908)
			(size 0.4572 0.4572)
			(layers "F.Cu" "F.Mask" "F.Paste")
			(net "GND")
		)
		(pad "K7" smd circle
			(at -17.100042 -14.249908)
			(size 0.4572 0.4572)
			(layers "F.Cu" "F.Mask" "F.Paste")
			(net "GND")
		)
		(pad "K8" smd circle
			(at -16.150082 -14.249908)
			(size 0.4572 0.4572)
			(layers "F.Cu" "F.Mask" "F.Paste")
			(net "GND")
		)
		(pad "K9" smd circle
			(at -15.200122 -14.249908)
			(size 0.4572 0.4572)
			(layers "F.Cu" "F.Mask" "F.Paste")
			(net "GND")
		)
		(pad "K10" smd circle
			(at -14.249908 -14.249908)
			(size 0.4572 0.4572)
			(layers "F.Cu" "F.Mask" "F.Paste")
			(net "GND")
		)
		(pad "K11" smd circle
			(at -13.299948 -14.249908)
			(size 0.4572 0.4572)
			(layers "F.Cu" "F.Mask" "F.Paste")
			(net "GND")
		)
		(pad "K12" smd circle
			(at -12.349988 -14.249908)
			(size 0.4572 0.4572)
			(layers "F.Cu" "F.Mask" "F.Paste")
			(net "GND")
		)
		(pad "K13" smd circle
			(at -11.400028 -14.249908)
			(size 0.4572 0.4572)
			(layers "F.Cu" "F.Mask" "F.Paste")
			(net "GND")
		)
		(pad "K14" smd circle
			(at -10.450068 -14.249908)
			(size 0.4572 0.4572)
			(layers "F.Cu" "F.Mask" "F.Paste")
			(net "GND")
		)
		(pad "K15" smd circle
			(at -9.500108 -14.249908)
			(size 0.4572 0.4572)
			(layers "F.Cu" "F.Mask" "F.Paste")
			(net "GND")
		)
		(pad "K16" smd circle
			(at -8.549894 -14.249908)
			(size 0.4572 0.4572)
			(layers "F.Cu" "F.Mask" "F.Paste")
			(net "GND")
		)
		(pad "K17" smd circle
			(at -7.599934 -14.249908)
			(size 0.4572 0.4572)
			(layers "F.Cu" "F.Mask" "F.Paste")
			(net "GND")
		)
		(pad "K18" smd circle
			(at -6.649974 -14.249908)
			(size 0.4572 0.4572)
			(layers "F.Cu" "F.Mask" "F.Paste")
			(net "GND")
		)
		(pad "K19" smd circle
			(at -5.700014 -14.249908)
			(size 0.4572 0.4572)
			(layers "F.Cu" "F.Mask" "F.Paste")
			(net "GND")
		)
		(pad "K20" smd circle
			(at -4.750054 -14.249908)
			(size 0.4572 0.4572)
			(layers "F.Cu" "F.Mask" "F.Paste")
			(net "GND")
		)
		(pad "K21" smd circle
			(at -3.800094 -14.249908)
			(size 0.4572 0.4572)
			(layers "F.Cu" "F.Mask" "F.Paste")
			(net "GND")
		)
		(pad "K22" smd circle
			(at -2.84988 -14.249908)
			(size 0.4572 0.4572)
			(layers "F.Cu" "F.Mask" "F.Paste")
			(net "GND")
		)
		(pad "K23" smd circle
			(at -1.89992 -14.249908)
			(size 0.4572 0.4572)
			(layers "F.Cu" "F.Mask" "F.Paste")
			(net "GND")
		)
		(pad "K24" smd circle
			(at -0.94996 -14.249908)
			(size 0.4572 0.4572)
			(layers "F.Cu" "F.Mask" "F.Paste")
			(net "GND")
		)
	)
)
